(kicad_pcb
	(version 20241229)
	(generator "pcbnew")
	(generator_version "9.0")
	(general
		(thickness 1.62)
		(legacy_teardrops no)
	)
	(paper "A3")
	(title_block
		(title "COM Express 7 Baseboard")
		(date "2025-02-04")
		(rev "1.1.2")
		(company "Antmicro Ltd")
		(comment 1 "www.antmicro.com")
		(comment 9 "footprint 489 of 802 (J12), pads 1-43 of 450")
	)
	(layers
		(0 "F.Cu" signal)
		(4 "In1.Cu" signal)
		(6 "In2.Cu" signal)
		(8 "In3.Cu" signal)
		(10 "In4.Cu" signal)
		(12 "In5.Cu" signal)
		(14 "In6.Cu" signal)
		(2 "B.Cu" signal)
		(9 "F.Adhes" user "F.Adhesive")
		(11 "B.Adhes" user "B.Adhesive")
		(13 "F.Paste" user)
		(15 "B.Paste" user)
		(5 "F.SilkS" user "F.Silkscreen")
		(7 "B.SilkS" user "B.Silkscreen")
		(1 "F.Mask" user)
		(3 "B.Mask" user)
		(17 "Dwgs.User" user "User.Drawings")
		(19 "Cmts.User" user "User.Comments")
		(21 "Eco1.User" user "User.Eco1")
		(23 "Eco2.User" user "User.Eco2")
		(25 "Edge.Cuts" user)
		(27 "Margin" user)
		(31 "F.CrtYd" user "F.Courtyard")
		(29 "B.CrtYd" user "B.Courtyard")
		(35 "F.Fab" user)
		(33 "B.Fab" user)
	)
	(footprint "antmicro-footprints:EPT_401-51501-51"
		(layer "F.Cu")
		(at 203.275 159.81)
		(property "Reference" "J12"
			(at 30.975 -10.45 0)
			(layer "F.SilkS")
			(effects
				(font
					(size 0.7 0.7)
					(thickness 0.15)
				)
				(justify right top)
			)
		)
		(property "Value" "Plug_Bus_CE7_EPT_401-51501-51"
			(at -3.225 52.665 0)
			(layer "F.Fab")
			(hide yes)
			(effects
				(font
					(size 0.7 0.7)
					(thickness 0.15)
				)
				(justify left top)
			)
		)
		(property "Datasheet" "https://www.farnell.com/datasheets/1905093.pdf"
			(at 0 0 0)
			(layer "F.Fab")
			(hide yes)
			(effects
				(font
					(size 1.27 1.27)
					(thickness 0.15)
				)
			)
		)
		(property "Author" "Antmicro"
			(at 406.55 319.62 0)
			(layer "F.Fab")
			(hide yes)
			(effects
				(font
					(size 1 1)
					(thickness 0.15)
				)
			)
		)
		(property "License" "Apache-2.0"
			(at 406.55 319.62 0)
			(layer "F.Fab")
			(hide yes)
			(effects
				(font
					(size 1 1)
					(thickness 0.15)
				)
			)
		)
		(property "MPN" "401-51501-51"
			(at 406.55 319.62 0)
			(layer "F.Fab")
			(hide yes)
			(effects
				(font
					(size 1 1)
					(thickness 0.15)
				)
			)
		)
		(property "Manufacturer" "ept"
			(at 406.55 319.62 0)
			(layer "F.Fab")
			(hide yes)
			(effects
				(font
					(size 1 1)
					(thickness 0.15)
				)
			)
		)
		(sheetname "Com Express 7 Interfaces")
		(sheetfile "com_express_7_interfaces.kicad_sch")
		(attr smd)
		(pad "" np_thru_hole circle
			(at -28.85 -6)
			(size 0.9 0.9)
			(drill 0.9)
			(layers "F&B.Cu" "*.Mask")
		)
		(pad "" smd rect
			(at -28.85 6 270)
			(size 0.001 0.001)
			(layers "F.Cu" "F.Mask" "F.Paste")
			(teardrops
				(best_length_ratio 0.2)
				(max_length 1)
				(best_width_ratio 0.9)
				(max_width 2)
				(curved_edges yes)
				(filter_ratio 0.9)
				(enabled yes)
				(allow_two_segments yes)
				(prefer_zone_connections yes)
			)
		)
		(pad "" np_thru_hole circle
			(at -28.85 6)
			(size 0.9 0.9)
			(drill 0.9)
			(layers "F&B.Cu" "*.Mask")
		)
		(pad "" np_thru_hole circle
			(at 28.85 -6)
			(size 1.6 1.6)
			(drill 1.6)
			(layers "F&B.Cu" "*.Mask")
		)
		(pad "" np_thru_hole circle
			(at 28.85 6)
			(size 1.6 1.6)
			(drill 1.6)
			(layers "F&B.Cu" "*.Mask")
		)
		(pad "A1" smd rect
			(at -27.25 8.875)
			(size 0.3 1.75)
			(layers "F.Cu" "F.Mask" "F.Paste")
			(net 1 "GND")
			(pinfunction "GND(FIXED)")
			(pintype "power_in")
			(teardrops
				(best_length_ratio 0.2)
				(max_length 1)
				(best_width_ratio 0.9)
				(max_width 2)
				(curved_edges yes)
				(filter_ratio 0.9)
				(enabled yes)
				(allow_two_segments yes)
				(prefer_zone_connections yes)
			)
		)
		(pad "A2" smd rect
			(at -26.75 8.875)
			(size 0.3 1.75)
			(layers "F.Cu" "F.Mask" "F.Paste")
			(net 285 "/2xUSB3.0+RJ45/GbE.MDI3-")
			(pinfunction "GBE0_MDI3-")
			(pintype "bidirectional")
			(teardrops
				(best_length_ratio 0.2)
				(max_length 1)
				(best_width_ratio 0.9)
				(max_width 2)
				(curved_edges yes)
				(filter_ratio 0.9)
				(enabled yes)
				(allow_two_segments yes)
				(prefer_zone_connections yes)
			)
		)
		(pad "A3" smd rect
			(at -26.25 8.875)
			(size 0.3 1.75)
			(layers "F.Cu" "F.Mask" "F.Paste")
			(net 286 "/2xUSB3.0+RJ45/GbE.MDI3+")
			(pinfunction "GBE0_MDI3+")
			(pintype "bidirectional")
			(teardrops
				(best_length_ratio 0.2)
				(max_length 1)
				(best_width_ratio 0.9)
				(max_width 2)
				(curved_edges yes)
				(filter_ratio 0.9)
				(enabled yes)
				(allow_two_segments yes)
				(prefer_zone_connections yes)
			)
		)
		(pad "A4" smd rect
			(at -25.75 8.875)
			(size 0.3 1.75)
			(layers "F.Cu" "F.Mask" "F.Paste")
			(net 287 "unconnected-(J12B-~{GBE0_LINK100}-PadA4)")
			(pinfunction "~{GBE0_LINK100}")
			(pintype "output+no_connect")
			(teardrops
				(best_length_ratio 0.2)
				(max_length 1)
				(best_width_ratio 0.9)
				(max_width 2)
				(curved_edges yes)
				(filter_ratio 0.9)
				(enabled yes)
				(allow_two_segments yes)
				(prefer_zone_connections yes)
			)
		)
		(pad "A5" smd rect
			(at -25.25 8.875)
			(size 0.3 1.75)
			(layers "F.Cu" "F.Mask" "F.Paste")
			(net 288 "/2xUSB3.0+RJ45/~{GBE0_LINK_1000}")
			(pinfunction "~{GBE0_LINK1000}")
			(pintype "output")
			(teardrops
				(best_length_ratio 0.2)
				(max_length 1)
				(best_width_ratio 0.9)
				(max_width 2)
				(curved_edges yes)
				(filter_ratio 0.9)
				(enabled yes)
				(allow_two_segments yes)
				(prefer_zone_connections yes)
			)
		)
		(pad "A6" smd rect
			(at -24.75 8.875)
			(size 0.3 1.75)
			(layers "F.Cu" "F.Mask" "F.Paste")
			(net 289 "/2xUSB3.0+RJ45/GbE.MDI2-")
			(pinfunction "GBE0_MDI2-")
			(pintype "bidirectional")
			(teardrops
				(best_length_ratio 0.2)
				(max_length 1)
				(best_width_ratio 0.9)
				(max_width 2)
				(curved_edges yes)
				(filter_ratio 0.9)
				(enabled yes)
				(allow_two_segments yes)
				(prefer_zone_connections yes)
			)
		)
		(pad "A7" smd rect
			(at -24.25 8.875)
			(size 0.3 1.75)
			(layers "F.Cu" "F.Mask" "F.Paste")
			(net 290 "/2xUSB3.0+RJ45/GbE.MDI2+")
			(pinfunction "GBE0_MDI2+")
			(pintype "bidirectional")
			(teardrops
				(best_length_ratio 0.2)
				(max_length 1)
				(best_width_ratio 0.9)
				(max_width 2)
				(curved_edges yes)
				(filter_ratio 0.9)
				(enabled yes)
				(allow_two_segments yes)
				(prefer_zone_connections yes)
			)
		)
		(pad "A8" smd rect
			(at -23.75 8.875)
			(size 0.3 1.75)
			(layers "F.Cu" "F.Mask" "F.Paste")
			(net 291 "/2xUSB3.0+RJ45/~{GBE0_LINK}")
			(pinfunction "~{GBE0_LINK}")
			(pintype "output")
			(teardrops
				(best_length_ratio 0.2)
				(max_length 1)
				(best_width_ratio 0.9)
				(max_width 2)
				(curved_edges yes)
				(filter_ratio 0.9)
				(enabled yes)
				(allow_two_segments yes)
				(prefer_zone_connections yes)
			)
		)
		(pad "A9" smd rect
			(at -23.25 8.875)
			(size 0.3 1.75)
			(layers "F.Cu" "F.Mask" "F.Paste")
			(net 292 "/2xUSB3.0+RJ45/GbE.MDI1-")
			(pinfunction "GBE0_MDI1-")
			(pintype "bidirectional")
			(teardrops
				(best_length_ratio 0.2)
				(max_length 1)
				(best_width_ratio 0.9)
				(max_width 2)
				(curved_edges yes)
				(filter_ratio 0.9)
				(enabled yes)
				(allow_two_segments yes)
				(prefer_zone_connections yes)
			)
		)
		(pad "A10" smd rect
			(at -22.75 8.875)
			(size 0.3 1.75)
			(layers "F.Cu" "F.Mask" "F.Paste")
			(net 293 "/2xUSB3.0+RJ45/GbE.MDI1+")
			(pinfunction "GBE0_MDI1+")
			(pintype "bidirectional")
			(teardrops
				(best_length_ratio 0.2)
				(max_length 1)
				(best_width_ratio 0.9)
				(max_width 2)
				(curved_edges yes)
				(filter_ratio 0.9)
				(enabled yes)
				(allow_two_segments yes)
				(prefer_zone_connections yes)
			)
		)
		(pad "A11" smd rect
			(at -22.25 8.875)
			(size 0.3 1.75)
			(layers "F.Cu" "F.Mask" "F.Paste")
			(net 1 "GND")
			(pinfunction "GND(FIXED)")
			(pintype "passive")
			(teardrops
				(best_length_ratio 0.2)
				(max_length 1)
				(best_width_ratio 0.9)
				(max_width 2)
				(curved_edges yes)
				(filter_ratio 0.9)
				(enabled yes)
				(allow_two_segments yes)
				(prefer_zone_connections yes)
			)
		)
		(pad "A12" smd rect
			(at -21.75 8.875)
			(size 0.3 1.75)
			(layers "F.Cu" "F.Mask" "F.Paste")
			(net 294 "/2xUSB3.0+RJ45/GbE.MDI0-")
			(pinfunction "GBE0_MDI0-")
			(pintype "bidirectional")
			(teardrops
				(best_length_ratio 0.2)
				(max_length 1)
				(best_width_ratio 0.9)
				(max_width 2)
				(curved_edges yes)
				(filter_ratio 0.9)
				(enabled yes)
				(allow_two_segments yes)
				(prefer_zone_connections yes)
			)
		)
		(pad "A13" smd rect
			(at -21.25 8.875)
			(size 0.3 1.75)
			(layers "F.Cu" "F.Mask" "F.Paste")
			(net 295 "/2xUSB3.0+RJ45/GbE.MDI0+")
			(pinfunction "GBE0_MDI0+")
			(pintype "bidirectional")
			(teardrops
				(best_length_ratio 0.2)
				(max_length 1)
				(best_width_ratio 0.9)
				(max_width 2)
				(curved_edges yes)
				(filter_ratio 0.9)
				(enabled yes)
				(allow_two_segments yes)
				(prefer_zone_connections yes)
			)
		)
		(pad "A14" smd rect
			(at -20.75 8.875)
			(size 0.3 1.75)
			(layers "F.Cu" "F.Mask" "F.Paste")
			(net 296 "/2xUSB3.0+RJ45/GbE.CTREF")
			(pinfunction "GBE0_CTREF")
			(pintype "passive")
			(teardrops
				(best_length_ratio 0.2)
				(max_length 1)
				(best_width_ratio 0.9)
				(max_width 2)
				(curved_edges yes)
				(filter_ratio 0.9)
				(enabled yes)
				(allow_two_segments yes)
				(prefer_zone_connections yes)
			)
		)
		(pad "A15" smd rect
			(at -20.25 8.875)
			(size 0.3 1.75)
			(layers "F.Cu" "F.Mask" "F.Paste")
			(net 297 "Net-(J12D-~{SUS_S3})")
			(pinfunction "~{SUS_S3}")
			(pintype "output")
			(teardrops
				(best_length_ratio 0.2)
				(max_length 1)
				(best_width_ratio 0.9)
				(max_width 2)
				(curved_edges yes)
				(filter_ratio 0.9)
				(enabled yes)
				(allow_two_segments yes)
				(prefer_zone_connections yes)
			)
		)
		(pad "A16" smd rect
			(at -19.75 8.875)
			(size 0.3 1.75)
			(layers "F.Cu" "F.Mask" "F.Paste")
			(net 298 "unconnected-(J12F-SATA0_TX+-PadA16)")
			(pinfunction "SATA0_TX+")
			(pintype "output+no_connect")
			(teardrops
				(best_length_ratio 0.2)
				(max_length 1)
				(best_width_ratio 0.9)
				(max_width 2)
				(curved_edges yes)
				(filter_ratio 0.9)
				(enabled yes)
				(allow_two_segments yes)
				(prefer_zone_connections yes)
			)
		)
		(pad "A17" smd rect
			(at -19.25 8.875)
			(size 0.3 1.75)
			(layers "F.Cu" "F.Mask" "F.Paste")
			(net 299 "unconnected-(J12F-SATA0_TX--PadA17)")
			(pinfunction "SATA0_TX-")
			(pintype "output+no_connect")
			(teardrops
				(best_length_ratio 0.2)
				(max_length 1)
				(best_width_ratio 0.9)
				(max_width 2)
				(curved_edges yes)
				(filter_ratio 0.9)
				(enabled yes)
				(allow_two_segments yes)
				(prefer_zone_connections yes)
			)
		)
		(pad "A18" smd rect
			(at -18.75 8.875)
			(size 0.3 1.75)
			(layers "F.Cu" "F.Mask" "F.Paste")
			(net 300 "Net-(J12D-~{SUS_S4})")
			(pinfunction "~{SUS_S4}")
			(pintype "output")
			(teardrops
				(best_length_ratio 0.2)
				(max_length 1)
				(best_width_ratio 0.9)
				(max_width 2)
				(curved_edges yes)
				(filter_ratio 0.9)
				(enabled yes)
				(allow_two_segments yes)
				(prefer_zone_connections yes)
			)
		)
		(pad "A19" smd rect
			(at -18.25 8.875)
			(size 0.3 1.75)
			(layers "F.Cu" "F.Mask" "F.Paste")
			(net 301 "unconnected-(J12F-SATA0_RX+-PadA19)")
			(pinfunction "SATA0_RX+")
			(pintype "input+no_connect")
			(teardrops
				(best_length_ratio 0.2)
				(max_length 1)
				(best_width_ratio 0.9)
				(max_width 2)
				(curved_edges yes)
				(filter_ratio 0.9)
				(enabled yes)
				(allow_two_segments yes)
				(prefer_zone_connections yes)
			)
		)
		(pad "A20" smd rect
			(at -17.75 8.875)
			(size 0.3 1.75)
			(layers "F.Cu" "F.Mask" "F.Paste")
			(net 302 "unconnected-(J12F-SATA0_RX--PadA20)")
			(pinfunction "SATA0_RX-")
			(pintype "input+no_connect")
			(teardrops
				(best_length_ratio 0.2)
				(max_length 1)
				(best_width_ratio 0.9)
				(max_width 2)
				(curved_edges yes)
				(filter_ratio 0.9)
				(enabled yes)
				(allow_two_segments yes)
				(prefer_zone_connections yes)
			)
		)
		(pad "A21" smd rect
			(at -17.25 8.875)
			(size 0.3 1.75)
			(layers "F.Cu" "F.Mask" "F.Paste")
			(net 1 "GND")
			(pinfunction "GND(FIXED)")
			(pintype "passive")
			(teardrops
				(best_length_ratio 0.2)
				(max_length 1)
				(best_width_ratio 0.9)
				(max_width 2)
				(curved_edges yes)
				(filter_ratio 0.9)
				(enabled yes)
				(allow_two_segments yes)
				(prefer_zone_connections yes)
			)
		)
		(pad "A22" smd rect
			(at -16.75 8.875)
			(size 0.3 1.75)
			(layers "F.Cu" "F.Mask" "F.Paste")
			(net 242 "/Com Express 7 Interfaces/PCIe_{B2Bx4}.TX3+")
			(pinfunction "PCIE_TX15+")
			(pintype "output")
			(teardrops
				(best_length_ratio 0.2)
				(max_length 1)
				(best_width_ratio 0.9)
				(max_width 2)
				(curved_edges yes)
				(filter_ratio 0.9)
				(enabled yes)
				(allow_two_segments yes)
				(prefer_zone_connections yes)
			)
		)
		(pad "A23" smd rect
			(at -16.25 8.875)
			(size 0.3 1.75)
			(layers "F.Cu" "F.Mask" "F.Paste")
			(net 241 "/Com Express 7 Interfaces/PCIe_{B2Bx4}.TX3-")
			(pinfunction "PCIE_TX15-")
			(pintype "output")
			(teardrops
				(best_length_ratio 0.2)
				(max_length 1)
				(best_width_ratio 0.9)
				(max_width 2)
				(curved_edges yes)
				(filter_ratio 0.9)
				(enabled yes)
				(allow_two_segments yes)
				(prefer_zone_connections yes)
			)
		)
		(pad "A24" smd rect
			(at -15.75 8.875)
			(size 0.3 1.75)
			(layers "F.Cu" "F.Mask" "F.Paste")
			(net 303 "/Com Express 7 MGMT/~{SUS_S5}")
			(pinfunction "~{SUS_S5}")
			(pintype "output")
			(teardrops
				(best_length_ratio 0.2)
				(max_length 1)
				(best_width_ratio 0.9)
				(max_width 2)
				(curved_edges yes)
				(filter_ratio 0.9)
				(enabled yes)
				(allow_two_segments yes)
				(prefer_zone_connections yes)
			)
		)
		(pad "A25" smd rect
			(at -15.25 8.875)
			(size 0.3 1.75)
			(layers "F.Cu" "F.Mask" "F.Paste")
			(net 249 "/Com Express 7 Interfaces/PCIe_{B2Bx4}.TX2+")
			(pinfunction "PCIE_TX14+")
			(pintype "output")
			(teardrops
				(best_length_ratio 0.2)
				(max_length 1)
				(best_width_ratio 0.9)
				(max_width 2)
				(curved_edges yes)
				(filter_ratio 0.9)
				(enabled yes)
				(allow_two_segments yes)
				(prefer_zone_connections yes)
			)
		)
		(pad "A26" smd rect
			(at -14.75 8.875)
			(size 0.3 1.75)
			(layers "F.Cu" "F.Mask" "F.Paste")
			(net 247 "/Com Express 7 Interfaces/PCIe_{B2Bx4}.TX2-")
			(pinfunction "PCIE_TX14-")
			(pintype "output")
			(teardrops
				(best_length_ratio 0.2)
				(max_length 1)
				(best_width_ratio 0.9)
				(max_width 2)
				(curved_edges yes)
				(filter_ratio 0.9)
				(enabled yes)
				(allow_two_segments yes)
				(prefer_zone_connections yes)
			)
		)
		(pad "A27" smd rect
			(at -14.25 8.875)
			(size 0.3 1.75)
			(layers "F.Cu" "F.Mask" "F.Paste")
			(net 304 "Net-(J12D-~{BATLOW})")
			(pinfunction "~{BATLOW}")
			(pintype "input")
			(teardrops
				(best_length_ratio 0.2)
				(max_length 1)
				(best_width_ratio 0.9)
				(max_width 2)
				(curved_edges yes)
				(filter_ratio 0.9)
				(enabled yes)
				(allow_two_segments yes)
				(prefer_zone_connections yes)
			)
		)
		(pad "A28" smd rect
			(at -13.75 8.875)
			(size 0.3 1.75)
			(layers "F.Cu" "F.Mask" "F.Paste")
			(net 305 "unconnected-(J12F-~{(S)ATA_ACT}-PadA28)")
			(pinfunction "~{(S)ATA_ACT}")
			(pintype "bidirectional+no_connect")
			(teardrops
				(best_length_ratio 0.2)
				(max_length 1)
				(best_width_ratio 0.9)
				(max_width 2)
				(curved_edges yes)
				(filter_ratio 0.9)
				(enabled yes)
				(allow_two_segments yes)
				(prefer_zone_connections yes)
			)
		)
		(pad "A29" smd rect
			(at -13.25 8.875)
			(size 0.3 1.75)
			(layers "F.Cu" "F.Mask" "F.Paste")
			(net 306 "unconnected-(J12H-RSVD-PadA29)")
			(pinfunction "RSVD")
			(pintype "no_connect")
			(teardrops
				(best_length_ratio 0.2)
				(max_length 1)
				(best_width_ratio 0.9)
				(max_width 2)
				(curved_edges yes)
				(filter_ratio 0.9)
				(enabled yes)
				(allow_two_segments yes)
				(prefer_zone_connections yes)
			)
		)
		(pad "A30" smd rect
			(at -12.75 8.875)
			(size 0.3 1.75)
			(layers "F.Cu" "F.Mask" "F.Paste")
			(net 307 "unconnected-(J12H-RSVD-PadA30)")
			(pinfunction "RSVD")
			(pintype "no_connect")
			(teardrops
				(best_length_ratio 0.2)
				(max_length 1)
				(best_width_ratio 0.9)
				(max_width 2)
				(curved_edges yes)
				(filter_ratio 0.9)
				(enabled yes)
				(allow_two_segments yes)
				(prefer_zone_connections yes)
			)
		)
		(pad "A31" smd rect
			(at -12.25 8.875)
			(size 0.3 1.75)
			(layers "F.Cu" "F.Mask" "F.Paste")
			(net 1 "GND")
			(pinfunction "GND(FIXED)")
			(pintype "passive")
			(teardrops
				(best_length_ratio 0.2)
				(max_length 1)
				(best_width_ratio 0.9)
				(max_width 2)
				(curved_edges yes)
				(filter_ratio 0.9)
				(enabled yes)
				(allow_two_segments yes)
				(prefer_zone_connections yes)
			)
		)
		(pad "A32" smd rect
			(at -11.75 8.875)
			(size 0.3 1.75)
			(layers "F.Cu" "F.Mask" "F.Paste")
			(net 308 "unconnected-(J12H-RSVD-PadA32)")
			(pinfunction "RSVD")
			(pintype "no_connect")
			(teardrops
				(best_length_ratio 0.2)
				(max_length 1)
				(best_width_ratio 0.9)
				(max_width 2)
				(curved_edges yes)
				(filter_ratio 0.9)
				(enabled yes)
				(allow_two_segments yes)
				(prefer_zone_connections yes)
			)
		)
		(pad "A33" smd rect
			(at -11.25 8.875)
			(size 0.3 1.75)
			(layers "F.Cu" "F.Mask" "F.Paste")
			(net 309 "unconnected-(J12H-RSVD-PadA33)")
			(pinfunction "RSVD")
			(pintype "no_connect")
			(teardrops
				(best_length_ratio 0.2)
				(max_length 1)
				(best_width_ratio 0.9)
				(max_width 2)
				(curved_edges yes)
				(filter_ratio 0.9)
				(enabled yes)
				(allow_two_segments yes)
				(prefer_zone_connections yes)
			)
		)
		(pad "A34" smd rect
			(at -10.75 8.875)
			(size 0.3 1.75)
			(layers "F.Cu" "F.Mask" "F.Paste")
			(net 310 "/Com Express 7 MGMT/~{BIOS_DIS0}")
			(pinfunction "~{BIOS_DIS0}/ESPI_SAFS")
			(pintype "input")
			(teardrops
				(best_length_ratio 0.2)
				(max_length 1)
				(best_width_ratio 0.9)
				(max_width 2)
				(curved_edges yes)
				(filter_ratio 0.9)
				(enabled yes)
				(allow_two_segments yes)
				(prefer_zone_connections yes)
			)
		)
		(pad "A35" smd rect
			(at -10.25 8.875)
			(size 0.3 1.75)
			(layers "F.Cu" "F.Mask" "F.Paste")
			(net 311 "Net-(J12D-~{THRMTRIP})")
			(pinfunction "~{THRMTRIP}")
			(pintype "output")
			(teardrops
				(best_length_ratio 0.2)
				(max_length 1)
				(best_width_ratio 0.9)
				(max_width 2)
				(curved_edges yes)
				(filter_ratio 0.9)
				(enabled yes)
				(allow_two_segments yes)
				(prefer_zone_connections yes)
			)
		)
		(pad "A36" smd rect
			(at -9.75 8.875)
			(size 0.3 1.75)
			(layers "F.Cu" "F.Mask" "F.Paste")
			(net 259 "/Com Express 7 Interfaces/PCIe_{B2Bx4}.TX1+")
			(pinfunction "PCIE_TX13+")
			(pintype "output")
			(teardrops
				(best_length_ratio 0.2)
				(max_length 1)
				(best_width_ratio 0.9)
				(max_width 2)
				(curved_edges yes)
				(filter_ratio 0.9)
				(enabled yes)
				(allow_two_segments yes)
				(prefer_zone_connections yes)
			)
		)
		(pad "A37" smd rect
			(at -9.25 8.875)
			(size 0.3 1.75)
			(layers "F.Cu" "F.Mask" "F.Paste")
			(net 257 "/Com Express 7 Interfaces/PCIe_{B2Bx4}.TX1-")
			(pinfunction "PCIE_TX13-")
			(pintype "output")
			(teardrops
				(best_length_ratio 0.2)
				(max_length 1)
				(best_width_ratio 0.9)
				(max_width 2)
				(curved_edges yes)
				(filter_ratio 0.9)
				(enabled yes)
				(allow_two_segments yes)
				(prefer_zone_connections yes)
			)
		)
		(pad "A38" smd rect
			(at -8.75 8.875)
			(size 0.3 1.75)
			(layers "F.Cu" "F.Mask" "F.Paste")
			(net 1 "GND")
			(pinfunction "GND")
			(pintype "power_in")
			(teardrops
				(best_length_ratio 0.2)
				(max_length 1)
				(best_width_ratio 0.9)
				(max_width 2)
				(curved_edges yes)
				(filter_ratio 0.9)
				(enabled yes)
				(allow_two_segments yes)
				(prefer_zone_connections yes)
			)
		)
	)
)
